(kicad_pcb
	(version 20241229)
	(generator "pcbnew")
	(generator_version "9.0")
	(general
		(thickness 1.552)
		(legacy_teardrops no)
	)
	(paper "A4")
	(title_block
		(date "2023-07-25")
		(rev "1.1.4")
		(comment 9 "footprints 304-308 of 379")
	)
	(layers
		(0 "F.Cu" signal)
		(4 "In1.Cu" signal)
		(6 "In2.Cu" signal)
		(8 "In3.Cu" signal)
		(10 "In4.Cu" signal)
		(12 "In5.Cu" signal)
		(14 "In6.Cu" signal)
		(2 "B.Cu" signal)
		(9 "F.Adhes" user "F.Adhesive")
		(11 "B.Adhes" user "B.Adhesive")
		(13 "F.Paste" user)
		(15 "B.Paste" user)
		(5 "F.SilkS" user "F.Silkscreen")
		(7 "B.SilkS" user "B.Silkscreen")
		(1 "F.Mask" user)
		(3 "B.Mask" user)
		(17 "Dwgs.User" user "User.Drawings")
		(19 "Cmts.User" user "User.Comments")
		(21 "Eco1.User" user "User.Eco1")
		(23 "Eco2.User" user "User.Eco2")
		(25 "Edge.Cuts" user)
		(27 "Margin" user)
		(31 "F.CrtYd" user "F.Courtyard")
		(29 "B.CrtYd" user "B.Courtyard")
		(35 "F.Fab" user)
		(33 "B.Fab" user)
	)
	(footprint "antmicro-footprints:C_0402_1005Metric"
		(layer "B.Cu")
		(at 101.8 76.38 180)
		(descr "Capacitor SMD 0402")
		(tags "capacitor SMD 0402")
		(property "Reference" "C74"
			(at -1.03 0.64 0)
			(layer "B.SilkS")
			(effects
				(font
					(size 0.65 0.65)
					(thickness 0.15)
				)
				(justify left bottom mirror)
			)
		)
		(property "Value" "C_100n_0402"
			(at 0 -1.4 0)
			(layer "B.Fab")
			(hide yes)
			(effects
				(font
					(size 0.7 0.7)
					(thickness 0.15)
				)
				(justify left bottom mirror)
			)
		)
		(property "Datasheet" "https://www.murata.com/products/productdetail?partno=GRM155R61H104KE14%23"
			(at 0 0 180)
			(layer "F.Fab")
			(hide yes)
			(effects
				(font
					(size 1.27 1.27)
					(thickness 0.15)
				)
			)
		)
		(property "Description" "SMD Multilayer Ceramic Capacitor, 0.1 µF, 50 V, 0402 [1005 Metric], ± 10%, X5R, GRM Series"
			(at 0 0 180)
			(layer "F.Fab")
			(hide yes)
			(effects
				(font
					(size 1.27 1.27)
					(thickness 0.15)
				)
			)
		)
		(property "Author" "Antmicro"
			(at 203.6 152.76 0)
			(layer "B.Fab")
			(hide yes)
			(effects
				(font
					(size 1 1)
					(thickness 0.15)
				)
				(justify mirror)
			)
		)
		(property "Dielectric" "X5R"
			(at 203.6 152.76 0)
			(layer "B.Fab")
			(hide yes)
			(effects
				(font
					(size 1 1)
					(thickness 0.15)
				)
				(justify mirror)
			)
		)
		(property "License" "Apache-2.0"
			(at 203.6 152.76 0)
			(layer "B.Fab")
			(hide yes)
			(effects
				(font
					(size 1 1)
					(thickness 0.15)
				)
				(justify mirror)
			)
		)
		(property "MPN" "GRM155R61H104KE14D"
			(at 203.6 152.76 0)
			(layer "B.Fab")
			(hide yes)
			(effects
				(font
					(size 1 1)
					(thickness 0.15)
				)
				(justify mirror)
			)
		)
		(property "Manufacturer" "Murata"
			(at 203.6 152.76 0)
			(layer "B.Fab")
			(hide yes)
			(effects
				(font
					(size 1 1)
					(thickness 0.15)
				)
				(justify mirror)
			)
		)
		(property "Val" "100n"
			(at 203.6 152.76 0)
			(layer "B.Fab")
			(hide yes)
			(effects
				(font
					(size 1 1)
					(thickness 0.15)
				)
				(justify mirror)
			)
		)
		(property "Voltage" "50V"
			(at 203.6 152.76 0)
			(layer "B.Fab")
			(hide yes)
			(effects
				(font
					(size 1 1)
					(thickness 0.15)
				)
				(justify mirror)
			)
		)
		(sheetname "/SDI/")
		(sheetfile "sdi.kicad_sch")
		(attr smd)
		(fp_rect
			(start -0.925 0.47)
			(end 0.925 -0.47)
			(stroke
				(width 0.05)
				(type default)
			)
			(fill no)
			(layer "B.CrtYd")
		)
		(fp_line
			(start 0.504 0.25)
			(end 0.504 -0.248)
			(stroke
				(width 0.15)
				(type solid)
			)
			(layer "B.Fab")
		)
		(fp_line
			(start 0.504 -0.248)
			(end -0.494 -0.248)
			(stroke
				(width 0.15)
				(type solid)
			)
			(layer "B.Fab")
		)
		(fp_line
			(start -0.494 0.25)
			(end 0.504 0.25)
			(stroke
				(width 0.15)
				(type solid)
			)
			(layer "B.Fab")
		)
		(fp_line
			(start -0.494 -0.248)
			(end -0.494 0.25)
			(stroke
				(width 0.15)
				(type solid)
			)
			(layer "B.Fab")
		)
		(fp_text user "License: Apache-2.0"
			(at -0.939 -5.799 0)
			(layer "B.Fab")
			(effects
				(font
					(size 0.7 0.7)
					(thickness 0.15)
				)
				(justify left bottom mirror)
			)
		)
		(fp_text user "Author: Antmicro"
			(at -0.939 -3.399 0)
			(layer "B.Fab")
			(effects
				(font
					(size 0.7 0.7)
					(thickness 0.15)
				)
				(justify left bottom mirror)
			)
		)
		(fp_text user "${REFERENCE}"
			(at -0.939 -4.599 0)
			(layer "B.Fab")
			(effects
				(font
					(size 0.7 0.7)
					(thickness 0.15)
				)
				(justify left bottom mirror)
			)
		)
		(pad "1" smd roundrect
			(at -0.48 0 180)
			(size 0.59 0.64)
			(layers "B.Cu" "B.Mask" "B.Paste")
			(roundrect_rratio 0.25)
			(net 1 "GND")
			(pintype "passive")
		)
		(pad "2" smd roundrect
			(at 0.48 0 180)
			(size 0.59 0.64)
			(layers "B.Cu" "B.Mask" "B.Paste")
			(roundrect_rratio 0.25)
			(net 2 "+3V3")
			(pintype "passive")
		)
	)
	(footprint "antmicro-footprints:C_0201"
		(layer "B.Cu")
		(at 126.3 89.9 90)
		(descr "Capacitor SMD 0201")
		(tags "capacitor SMD 0201")
		(property "Reference" "C118"
			(at 11.895736 -9.17 90)
			(layer "B.SilkS")
			(effects
				(font
					(size 0.65 0.65)
					(thickness 0.15)
				)
				(justify right bottom mirror)
			)
		)
		(property "Value" "C_100n_0201"
			(at 0 -1.4 90)
			(layer "B.Fab")
			(hide yes)
			(effects
				(font
					(size 0.7 0.7)
					(thickness 0.15)
				)
				(justify right bottom mirror)
			)
		)
		(property "Datasheet" "https://www.yageo.com/en/Chart/Download/pdf/CC0201KRX6S5BB104"
			(at 0 0 90)
			(layer "F.Fab")
			(hide yes)
			(effects
				(font
					(size 1.27 1.27)
					(thickness 0.15)
				)
			)
		)
		(property "Description" "SMD Multilayer Ceramic Capacitor, 0.1 µF, 6.3 V, 0201 [0603 Metric], ± 10%, X6S, CC Series"
			(at 0 0 90)
			(layer "F.Fab")
			(hide yes)
			(effects
				(font
					(size 1.27 1.27)
					(thickness 0.15)
				)
			)
		)
		(property "Author" "Antmicro"
			(at 216.2 -36.4 0)
			(layer "B.Fab")
			(hide yes)
			(effects
				(font
					(size 1 1)
					(thickness 0.15)
				)
				(justify mirror)
			)
		)
		(property "Dielectric" ""
			(at 216.2 -36.4 0)
			(layer "B.Fab")
			(hide yes)
			(effects
				(font
					(size 1 1)
					(thickness 0.15)
				)
				(justify mirror)
			)
		)
		(property "License" "Apache-2.0"
			(at 216.2 -36.4 0)
			(layer "B.Fab")
			(hide yes)
			(effects
				(font
					(size 1 1)
					(thickness 0.15)
				)
				(justify mirror)
			)
		)
		(property "MPN" "CC0201KRX6S5BB104"
			(at 216.2 -36.4 0)
			(layer "B.Fab")
			(hide yes)
			(effects
				(font
					(size 1 1)
					(thickness 0.15)
				)
				(justify mirror)
			)
		)
		(property "Manufacturer" "YAGEO"
			(at 216.2 -36.4 0)
			(layer "B.Fab")
			(hide yes)
			(effects
				(font
					(size 1 1)
					(thickness 0.15)
				)
				(justify mirror)
			)
		)
		(property "Val" "100n"
			(at 216.2 -36.4 0)
			(layer "B.Fab")
			(hide yes)
			(effects
				(font
					(size 1 1)
					(thickness 0.15)
				)
				(justify mirror)
			)
		)
		(property "Voltage" ""
			(at 216.2 -36.4 0)
			(layer "B.Fab")
			(hide yes)
			(effects
				(font
					(size 1 1)
					(thickness 0.15)
				)
				(justify mirror)
			)
		)
		(property "Public" "False"
			(at 0 0 90)
			(unlocked yes)
			(layer "B.Fab")
			(hide yes)
			(effects
				(font
					(size 1 1)
					(thickness 0.15)
				)
				(justify mirror)
			)
		)
		(sheetname "/FPGA Power/")
		(sheetfile "FPGA_Power.kicad_sch")
		(attr smd)
		(fp_rect
			(start -0.7 0.35)
			(end 0.7 -0.35)
			(stroke
				(width 0.05)
				(type default)
			)
			(fill no)
			(layer "B.CrtYd")
		)
		(fp_rect
			(start 0.3 -0.15)
			(end -0.301 0.149)
			(stroke
				(width 0.15)
				(type solid)
			)
			(fill no)
			(layer "B.Fab")
		)
		(fp_text user "License: Apache-2.0"
			(at -0.72 -4.4 270)
			(layer "B.Fab")
			(effects
				(font
					(size 0.7 0.7)
					(thickness 0.15)
				)
				(justify left bottom mirror)
			)
		)
		(fp_text user "Author: Antmicro"
			(at -0.72 -5.4 270)
			(layer "B.Fab")
			(effects
				(font
					(size 0.7 0.7)
					(thickness 0.15)
				)
				(justify left bottom mirror)
			)
		)
		(fp_text user "${REFERENCE}"
			(at -0.72 -3.4 270)
			(layer "B.Fab")
			(effects
				(font
					(size 0.7 0.7)
					(thickness 0.15)
				)
				(justify left bottom mirror)
			)
		)
		(pad "" smd roundrect
			(at -0.349 0.002 90)
			(size 0.318 0.36)
			(layers "B.Paste")
			(roundrect_rratio 0.25)
		)
		(pad "" smd roundrect
			(at 0.341 0.002 90)
			(size 0.318 0.36)
			(layers "B.Paste")
			(roundrect_rratio 0.25)
		)
		(pad "1" smd roundrect
			(at -0.321 0.002 90)
			(size 0.46 0.4)
			(layers "B.Cu" "B.Mask")
			(roundrect_rratio 0.25)
			(net 1 "GND")
			(pintype "passive")
		)
		(pad "2" smd roundrect
			(at 0.32 0.002 90)
			(size 0.46 0.4)
			(layers "B.Cu" "B.Mask")
			(roundrect_rratio 0.25)
			(net 9 "/FPGA Power/VCC_AUX")
			(pintype "passive")
		)
	)
	(footprint "antmicro-footprints:R_0402_1005Metric"
		(layer "B.Cu")
		(at 94.255 93.25)
		(descr "Resistor SMD 0402")
		(tags "resistor SMD 0402")
		(property "Reference" "R140"
			(at -1.025 0.29 180)
			(layer "B.SilkS")
			(effects
				(font
					(size 0.65 0.65)
					(thickness 0.15)
				)
				(justify left bottom mirror)
			)
		)
		(property "Value" "R_1k_0402"
			(at 0 -1.4 180)
			(layer "B.Fab")
			(hide yes)
			(effects
				(font
					(size 0.7 0.7)
					(thickness 0.15)
				)
				(justify left bottom mirror)
			)
		)
		(property "Datasheet" "https://www.bourns.com/docs/product-datasheets/cr.pdf"
			(at 0 0 0)
			(layer "F.Fab")
			(hide yes)
			(effects
				(font
					(size 1.27 1.27)
					(thickness 0.15)
				)
			)
		)
		(property "Description" "SMD Chip Resistor, 1 kohm, ± 1%, 63 mW, 0402 [1005 Metric], Thick Film, General Purpose"
			(at 0 0 0)
			(layer "F.Fab")
			(hide yes)
			(effects
				(font
					(size 1.27 1.27)
					(thickness 0.15)
				)
			)
		)
		(property "Author" "Antmicro"
			(at 0 0 0)
			(layer "B.Fab")
			(hide yes)
			(effects
				(font
					(size 1 1)
					(thickness 0.15)
				)
				(justify mirror)
			)
		)
		(property "License" "Apache-2.0"
			(at 0 0 0)
			(layer "B.Fab")
			(hide yes)
			(effects
				(font
					(size 1 1)
					(thickness 0.15)
				)
				(justify mirror)
			)
		)
		(property "MPN" "CR0402-FX-1001GLF"
			(at 0 0 0)
			(layer "B.Fab")
			(hide yes)
			(effects
				(font
					(size 1 1)
					(thickness 0.15)
				)
				(justify mirror)
			)
		)
		(property "Manufacturer" "Bourns"
			(at 0 0 0)
			(layer "B.Fab")
			(hide yes)
			(effects
				(font
					(size 1 1)
					(thickness 0.15)
				)
				(justify mirror)
			)
		)
		(property "Tolerance" "1%"
			(at 0 0 0)
			(layer "B.Fab")
			(hide yes)
			(effects
				(font
					(size 1 1)
					(thickness 0.15)
				)
				(justify mirror)
			)
		)
		(property "Val" "1k"
			(at 0 0 0)
			(layer "B.Fab")
			(hide yes)
			(effects
				(font
					(size 1 1)
					(thickness 0.15)
				)
				(justify mirror)
			)
		)
		(sheetname "/SDI/")
		(sheetfile "sdi.kicad_sch")
		(attr smd exclude_from_pos_files exclude_from_bom dnp)
		(fp_rect
			(start -0.925 0.47)
			(end 0.925 -0.47)
			(stroke
				(width 0.05)
				(type default)
			)
			(fill no)
			(layer "B.CrtYd")
		)
		(fp_rect
			(start -0.5 0.25)
			(end 0.5 -0.25)
			(stroke
				(width 0.15)
				(type solid)
			)
			(fill no)
			(layer "B.Fab")
		)
		(fp_text user "License: Apache-2.0"
			(at -0.95 -5.169 180)
			(layer "B.Fab")
			(effects
				(font
					(size 0.7 0.7)
					(thickness 0.15)
				)
				(justify left bottom mirror)
			)
		)
		(fp_text user "${REFERENCE}"
			(at -0.95 -3.168 180)
			(layer "B.Fab")
			(effects
				(font
					(size 0.7 0.7)
					(thickness 0.15)
				)
				(justify left bottom mirror)
			)
		)
		(fp_text user "Author: Antmicro"
			(at -0.95 -4.169 180)
			(layer "B.Fab")
			(effects
				(font
					(size 0.7 0.7)
					(thickness 0.15)
				)
				(justify left bottom mirror)
			)
		)
		(pad "1" smd roundrect
			(at -0.48 0)
			(size 0.59 0.64)
			(layers "B.Cu" "B.Mask" "B.Paste")
			(roundrect_rratio 0.25)
			(net 1 "GND")
			(pintype "passive")
		)
		(pad "2" smd roundrect
			(at 0.48 0)
			(size 0.59 0.64)
			(layers "B.Cu" "B.Mask" "B.Paste")
			(roundrect_rratio 0.25)
			(net 198 "/SDI/AUDIO_EN{slash}~{DIS}")
			(pintype "passive")
		)
	)
	(footprint "antmicro-footprints:C_0402_1005Metric"
		(layer "B.Cu")
		(at 91.58 75.36 90)
		(descr "Capacitor SMD 0402")
		(tags "capacitor SMD 0402")
		(property "Reference" "C73"
			(at -1.28 -0.65 90)
			(layer "B.SilkS")
			(effects
				(font
					(size 0.65 0.65)
					(thickness 0.15)
				)
				(justify right bottom mirror)
			)
		)
		(property "Value" "C_100n_0402"
			(at 0 -1.4 90)
			(layer "B.Fab")
			(hide yes)
			(effects
				(font
					(size 0.7 0.7)
					(thickness 0.15)
				)
				(justify right bottom mirror)
			)
		)
		(property "Datasheet" "https://www.murata.com/products/productdetail?partno=GRM155R61H104KE14%23"
			(at 0 0 90)
			(layer "F.Fab")
			(hide yes)
			(effects
				(font
					(size 1.27 1.27)
					(thickness 0.15)
				)
			)
		)
		(property "Description" "SMD Multilayer Ceramic Capacitor, 0.1 µF, 50 V, 0402 [1005 Metric], ± 10%, X5R, GRM Series"
			(at 0 0 90)
			(layer "F.Fab")
			(hide yes)
			(effects
				(font
					(size 1.27 1.27)
					(thickness 0.15)
				)
			)
		)
		(property "Author" "Antmicro"
			(at 166.94 -16.22 0)
			(layer "B.Fab")
			(hide yes)
			(effects
				(font
					(size 1 1)
					(thickness 0.15)
				)
				(justify mirror)
			)
		)
		(property "Dielectric" "X5R"
			(at 166.94 -16.22 0)
			(layer "B.Fab")
			(hide yes)
			(effects
				(font
					(size 1 1)
					(thickness 0.15)
				)
				(justify mirror)
			)
		)
		(property "License" "Apache-2.0"
			(at 166.94 -16.22 0)
			(layer "B.Fab")
			(hide yes)
			(effects
				(font
					(size 1 1)
					(thickness 0.15)
				)
				(justify mirror)
			)
		)
		(property "MPN" "GRM155R61H104KE14D"
			(at 166.94 -16.22 0)
			(layer "B.Fab")
			(hide yes)
			(effects
				(font
					(size 1 1)
					(thickness 0.15)
				)
				(justify mirror)
			)
		)
		(property "Manufacturer" "Murata"
			(at 166.94 -16.22 0)
			(layer "B.Fab")
			(hide yes)
			(effects
				(font
					(size 1 1)
					(thickness 0.15)
				)
				(justify mirror)
			)
		)
		(property "Val" "100n"
			(at 166.94 -16.22 0)
			(layer "B.Fab")
			(hide yes)
			(effects
				(font
					(size 1 1)
					(thickness 0.15)
				)
				(justify mirror)
			)
		)
		(property "Voltage" "50V"
			(at 166.94 -16.22 0)
			(layer "B.Fab")
			(hide yes)
			(effects
				(font
					(size 1 1)
					(thickness 0.15)
				)
				(justify mirror)
			)
		)
		(sheetname "/SDI/")
		(sheetfile "sdi.kicad_sch")
		(attr smd)
		(fp_rect
			(start -0.925 0.47)
			(end 0.925 -0.47)
			(stroke
				(width 0.05)
				(type default)
			)
			(fill no)
			(layer "B.CrtYd")
		)
		(fp_line
			(start 0.504 -0.248)
			(end -0.494 -0.248)
			(stroke
				(width 0.15)
				(type solid)
			)
			(layer "B.Fab")
		)
		(fp_line
			(start -0.494 -0.248)
			(end -0.494 0.25)
			(stroke
				(width 0.15)
				(type solid)
			)
			(layer "B.Fab")
		)
		(fp_line
			(start 0.504 0.25)
			(end 0.504 -0.248)
			(stroke
				(width 0.15)
				(type solid)
			)
			(layer "B.Fab")
		)
		(fp_line
			(start -0.494 0.25)
			(end 0.504 0.25)
			(stroke
				(width 0.15)
				(type solid)
			)
			(layer "B.Fab")
		)
		(fp_text user "${REFERENCE}"
			(at -0.939 -4.599 270)
			(layer "B.Fab")
			(effects
				(font
					(size 0.7 0.7)
					(thickness 0.15)
				)
				(justify left bottom mirror)
			)
		)
		(fp_text user "License: Apache-2.0"
			(at -0.939 -5.799 270)
			(layer "B.Fab")
			(effects
				(font
					(size 0.7 0.7)
					(thickness 0.15)
				)
				(justify left bottom mirror)
			)
		)
		(fp_text user "Author: Antmicro"
			(at -0.939 -3.399 270)
			(layer "B.Fab")
			(effects
				(font
					(size 0.7 0.7)
					(thickness 0.15)
				)
				(justify left bottom mirror)
			)
		)
		(pad "1" smd roundrect
			(at -0.48 0 90)
			(size 0.59 0.64)
			(layers "B.Cu" "B.Mask" "B.Paste")
			(roundrect_rratio 0.25)
			(net 1 "GND")
			(pintype "passive")
		)
		(pad "2" smd roundrect
			(at 0.48 0 90)
			(size 0.59 0.64)
			(layers "B.Cu" "B.Mask" "B.Paste")
			(roundrect_rratio 0.25)
			(net 3 "+1V2")
			(pintype "passive")
		)
	)
	(footprint "antmicro-footprints:FB_0603_1608Metric"
		(layer "B.Cu")
		(at 136.99 96.48)
		(property "Reference" "FB4"
			(at 3.54 0.41 180)
			(layer "B.SilkS")
			(effects
				(font
					(size 0.65 0.65)
					(thickness 0.15)
				)
				(justify left bottom mirror)
			)
		)
		(property "Value" "FB_120Z_2A_0603"
			(at 0 -1.5 180)
			(layer "B.Fab")
			(hide yes)
			(effects
				(font
					(size 0.7 0.7)
					(thickness 0.15)
				)
				(justify left bottom mirror)
			)
		)
		(property "Datasheet" "https://www.murata.com/en-us/products/productdata/8796738650142/ENFA0003.pdf"
			(at 0 0 0)
			(layer "F.Fab")
			(hide yes)
			(effects
				(font
					(size 1.27 1.27)
					(thickness 0.15)
				)
			)
		)
		(property "Description" "Ferrite Bead, 0603 [1608 Metric], 120 ohm, 2 A, BLM18P, 0.05 ohm, ± 25%, DC power line"
			(at 0 0 0)
			(layer "F.Fab")
			(hide yes)
			(effects
				(font
					(size 1.27 1.27)
					(thickness 0.15)
				)
			)
		)
		(property "Author" "Antmicro"
			(at 0 0 0)
			(layer "B.Fab")
			(hide yes)
			(effects
				(font
					(size 1 1)
					(thickness 0.15)
				)
				(justify mirror)
			)
		)
		(property "License" "Apache-2.0"
			(at 0 0 0)
			(layer "B.Fab")
			(hide yes)
			(effects
				(font
					(size 1 1)
					(thickness 0.15)
				)
				(justify mirror)
			)
		)
		(property "MPN" "BLM18PG121SN1D"
			(at 0 0 0)
			(layer "B.Fab")
			(hide yes)
			(effects
				(font
					(size 1 1)
					(thickness 0.15)
				)
				(justify mirror)
			)
		)
		(property "Manufacturer" "Murata"
			(at 0 0 0)
			(layer "B.Fab")
			(hide yes)
			(effects
				(font
					(size 1 1)
					(thickness 0.15)
				)
				(justify mirror)
			)
		)
		(property "Val" "120Z/2A"
			(at 0 0 0)
			(unlocked yes)
			(layer "B.Fab")
			(hide yes)
			(effects
				(font
					(size 1 1)
					(thickness 0.15)
				)
				(justify mirror)
			)
		)
		(property "Current" ""
			(at 0 0 0)
			(unlocked yes)
			(layer "B.Fab")
			(hide yes)
			(effects
				(font
					(size 1 1)
					(thickness 0.15)
				)
				(justify mirror)
			)
		)
		(sheetname "/FPGA Power/")
		(sheetfile "FPGA_Power.kicad_sch")
		(attr smd)
		(fp_line
			(start -0.15 -0.4)
			(end 0.15 -0.4)
			(stroke
				(width 0.15)
				(type solid)
			)
			(layer "B.SilkS")
		)
		(fp_line
			(start -0.15 0.4)
			(end 0.15 0.4)
			(stroke
				(width 0.15)
				(type solid)
			)
			(layer "B.SilkS")
		)
		(fp_rect
			(start -1.25 0.65)
			(end 1.25 -0.65)
			(stroke
				(width 0.05)
				(type solid)
			)
			(fill no)
			(layer "B.CrtYd")
		)
		(fp_line
			(start -0.803 -0.406)
			(end -0.803 0.408)
			(stroke
				(width 0.15)
				(type solid)
			)
			(layer "B.Fab")
		)
		(fp_line
			(start 0.8 -0.406)
			(end -0.803 -0.406)
			(stroke
				(width 0.15)
				(type solid)
			)
			(layer "B.Fab")
		)
		(fp_line
			(start 0.8 0.408)
			(end -0.803 0.408)
			(stroke
				(width 0.15)
				(type solid)
			)
			(layer "B.Fab")
		)
		(fp_line
			(start 0.8 0.408)
			(end 0.8 -0.406)
			(stroke
				(width 0.15)
				(type solid)
			)
			(layer "B.Fab")
		)
		(fp_text user "License: Apache-2.0"
			(at -1.653 -5.9 180)
			(layer "B.Fab")
			(effects
				(font
					(size 0.7 0.7)
					(thickness 0.15)
				)
				(justify left bottom mirror)
			)
		)
		(fp_text user "Author: Antmicro"
			(at -1.653 -3.162 180)
			(layer "B.Fab")
			(effects
				(font
					(size 0.7 0.7)
					(thickness 0.15)
				)
				(justify left bottom mirror)
			)
		)
		(fp_text user "${REFERENCE}"
			(at -1.653 -4.6 180)
			(layer "B.Fab")
			(effects
				(font
					(size 0.7 0.7)
					(thickness 0.15)
				)
				(justify left bottom mirror)
			)
		)
		(pad "1" smd roundrect
			(at -0.7 0)
			(size 0.8 1)
			(layers "B.Cu" "B.Mask" "B.Paste")
			(roundrect_rratio 0.2)
			(net 12 "/FPGA Power/VCC_ADPHY")
			(pintype "passive")
		)
		(pad "2" smd roundrect
			(at 0.7 0)
			(size 0.8 1)
			(layers "B.Cu" "B.Mask" "B.Paste")
			(roundrect_rratio 0.2)
			(net 50 "+1V8")
			(pintype "passive")
		)
	)
)
